(kicad_pcb
	(version 20260206)
	(generator "pcbnew")
	(generator_version "10.0")
	(general
		(thickness 1.6)
		(legacy_teardrops no)
	)
	(paper "A4")
	(title_block
		(title "Bryce Canyon_IOM_IOC_16318-2_OCP.brd")
		(comment 1 "Bryce Canyon / footprints 1388-1395 of 1605")
	)
	(layers
		(0 "F.Cu" signal "TOP")
		(4 "In1.Cu" signal "L2GND")
		(6 "In2.Cu" signal "L3")
		(8 "In3.Cu" signal "L4VCC")
		(10 "In4.Cu" signal "L5VCC")
		(12 "In5.Cu" signal "L6")
		(14 "In6.Cu" signal "L7GND")
		(2 "B.Cu" signal "BOTTOM")
		(9 "F.Adhes" user "F.Adhesive")
		(11 "B.Adhes" user "B.Adhesive")
		(13 "F.Paste" user "Package Geometry/Pastemask Top")
		(15 "B.Paste" user "Package Geometry/Pastemask Bottom")
		(5 "F.SilkS" user "Ref Des/Silkscreen Top")
		(7 "B.SilkS" user "Ref Des/Silkscreen Bottom")
		(1 "F.Mask" user "Board Geometry/Soldermask Top")
		(3 "B.Mask" user "Board Geometry/Soldermask Bottom")
		(17 "Dwgs.User" user "User.Drawings")
		(19 "Cmts.User" user "User.Comments")
		(21 "Eco1.User" user "User.Eco1")
		(23 "Eco2.User" user "User.Eco2")
		(25 "Edge.Cuts" user "Board Geometry/Outline")
		(27 "Margin" user)
		(31 "F.CrtYd" user "Package Geometry/Place Bound Top")
		(29 "B.CrtYd" user "Package Geometry/Place Bound Bottom")
		(35 "F.Fab" user "Ref Des/Assembly Top")
		(33 "B.Fab" user "Ref Des/Assembly Bottom")
	)
	(footprint ""
		(layer "B.Cu")
		(at 56.850026 -161.083752 90)
		(property "Reference" "C123"
			(at 0 0 90)
			(layer "B.SilkS")
			(hide yes)
			(effects
				(font
					(size 1.27 1.27)
				)
				(justify mirror)
			)
		)
		(property "Value" "SCD1U25V2KX-2-GP"
			(at -1.1811 -2.7051 90)
			(unlocked yes)
			(layer "B.Fab")
			(hide yes)
			(effects
				(font
					(size 1.016 1.016)
					(thickness 0.1524)
				)
				(justify mirror)
			)
		)
		(property "Device Type" "C402H22"
			(at -1.1811 -4.2291 90)
			(unlocked yes)
			(layer "B.Fab")
			(hide yes)
			(effects
				(font
					(size 1.016 1.016)
					(thickness 0.1524)
				)
				(justify mirror)
			)
		)
		(duplicate_pad_numbers_are_jumpers no)
		(fp_rect
			(start 0.4318 0.9525)
			(end -0.4318 -0.9525)
			(stroke
				(width 0)
				(type default)
			)
			(fill no)
			(layer "B.CrtYd")
		)
		(fp_rect
			(start 0.4318 0.9525)
			(end -0.4318 -0.9525)
			(stroke
				(width 0)
				(type default)
			)
			(fill no)
			(layer "B.Fab")
		)
		(pad "1" smd custom
			(at 0 -0.4445 270)
			(size 0.1524 0.1524)
			(layers "B.Cu" "B.Mask" "B.Paste")
			(net "ADC_P5V_STBY")
			(options
				(clearance outline)
				(anchor circle)
			)
			(primitives
				(gr_poly
					(pts
						(arc
							(start 0.3048 0.2032)
							(mid 0.275042 0.275042)
							(end 0.2032 0.3048)
						)
						(arc
							(start -0.2032 0.3048)
							(mid -0.275042 0.275042)
							(end -0.3048 0.2032)
						)
						(arc
							(start -0.3048 -0.2032)
							(mid -0.275042 -0.275042)
							(end -0.2032 -0.3048)
						)
						(arc
							(start 0.2032 -0.3048)
							(mid 0.275042 -0.275042)
							(end 0.3048 -0.2032)
						)
					)
					(width 0)
					(fill yes)
				)
			)
		)
		(pad "2" smd custom
			(at 0 0.4445 270)
			(size 0.1524 0.1524)
			(layers "B.Cu" "B.Mask" "B.Paste")
			(net "GND")
			(options
				(clearance outline)
				(anchor circle)
			)
			(primitives
				(gr_poly
					(pts
						(arc
							(start 0.3048 0.2032)
							(mid 0.275042 0.275042)
							(end 0.2032 0.3048)
						)
						(arc
							(start -0.2032 0.3048)
							(mid -0.275042 0.275042)
							(end -0.3048 0.2032)
						)
						(arc
							(start -0.3048 -0.2032)
							(mid -0.275042 -0.275042)
							(end -0.2032 -0.3048)
						)
						(arc
							(start 0.2032 -0.3048)
							(mid 0.275042 -0.275042)
							(end 0.3048 -0.2032)
						)
					)
					(width 0)
					(fill yes)
				)
			)
		)
	)
	(footprint ""
		(layer "B.Cu")
		(at 179.9082 -114.554)
		(property "Reference" "R567"
			(at 0 0 0)
			(layer "B.SilkS")
			(hide yes)
			(effects
				(font
					(size 1.27 1.27)
				)
				(justify mirror)
			)
		)
		(property "Value" "4K7R2F-GP"
			(at -0.064008 -3.993896 0)
			(unlocked yes)
			(layer "B.Fab")
			(hide yes)
			(effects
				(font
					(size 1.016 1.016)
					(thickness 0.1524)
				)
				(justify mirror)
			)
		)
		(property "Device Type" "R402H16"
			(at -0.064008 -5.517896 0)
			(unlocked yes)
			(layer "B.Fab")
			(hide yes)
			(effects
				(font
					(size 1.016 1.016)
					(thickness 0.1524)
				)
				(justify mirror)
			)
		)
		(duplicate_pad_numbers_are_jumpers no)
		(fp_line
			(start -0.508 -0.9398)
			(end 0.508 -0.9398)
			(stroke
				(width 0.1524)
				(type default)
			)
			(layer "B.SilkS")
		)
		(fp_line
			(start 0.508 -0.9398)
			(end 0.508 0.9398)
			(stroke
				(width 0.1524)
				(type default)
			)
			(layer "B.SilkS")
		)
		(fp_rect
			(start 0.508 0.9398)
			(end -0.508 -0.9398)
			(stroke
				(width 0)
				(type default)
			)
			(fill no)
			(layer "B.CrtYd")
		)
		(fp_rect
			(start 0.508 0.9398)
			(end -0.508 -0.9398)
			(stroke
				(width 0)
				(type default)
			)
			(fill no)
			(layer "B.Fab")
		)
		(pad "1" smd custom
			(at 0 -0.4445 180)
			(size 0.1397 0.1397)
			(layers "B.Cu" "B.Mask" "B.Paste")
			(net "IOM_FULL_PGOOD")
			(options
				(clearance outline)
				(anchor circle)
			)
			(primitives
				(gr_poly
					(pts
						(arc
							(start -0.1778 0.2794)
							(mid -0.249642 0.249642)
							(end -0.2794 0.1778)
						)
						(arc
							(start -0.2794 -0.1778)
							(mid -0.249642 -0.249642)
							(end -0.1778 -0.2794)
						)
						(arc
							(start 0.1778 -0.2794)
							(mid 0.249642 -0.249642)
							(end 0.2794 -0.1778)
						)
						(arc
							(start 0.2794 0.1778)
							(mid 0.249642 0.249642)
							(end 0.1778 0.2794)
						)
					)
					(width 0)
					(fill yes)
				)
			)
		)
		(pad "2" smd custom
			(at 0 0.4445 180)
			(size 0.1397 0.1397)
			(layers "B.Cu" "B.Mask" "B.Paste")
			(net "P3V3_STBY")
			(options
				(clearance outline)
				(anchor circle)
			)
			(primitives
				(gr_poly
					(pts
						(arc
							(start -0.1778 0.2794)
							(mid -0.249642 0.249642)
							(end -0.2794 0.1778)
						)
						(arc
							(start -0.2794 -0.1778)
							(mid -0.249642 -0.249642)
							(end -0.1778 -0.2794)
						)
						(arc
							(start 0.1778 -0.2794)
							(mid 0.249642 -0.249642)
							(end 0.2794 -0.1778)
						)
						(arc
							(start 0.2794 0.1778)
							(mid 0.249642 0.249642)
							(end 0.1778 0.2794)
						)
					)
					(width 0)
					(fill yes)
				)
			)
		)
	)
	(footprint ""
		(layer "B.Cu")
		(at 55.8165 -154.7241 90)
		(property "Reference" "C87"
			(at 0 0 90)
			(layer "B.SilkS")
			(hide yes)
			(effects
				(font
					(size 1.27 1.27)
				)
				(justify mirror)
			)
		)
		(property "Value" "SC1U16V3KX-5GP"
			(at 0 -2.8194 90)
			(unlocked yes)
			(layer "B.Fab")
			(hide yes)
			(effects
				(font
					(size 1.016 1.016)
					(thickness 0.1524)
				)
				(justify mirror)
			)
		)
		(property "Device Type" "C603H36"
			(at 0 -4.3434 90)
			(unlocked yes)
			(layer "B.Fab")
			(hide yes)
			(effects
				(font
					(size 1.016 1.016)
					(thickness 0.1524)
				)
				(justify mirror)
			)
		)
		(duplicate_pad_numbers_are_jumpers no)
		(fp_line
			(start -0.508 0)
			(end 0.508 0)
			(stroke
				(width 0.2032)
				(type default)
			)
			(layer "B.SilkS")
		)
		(fp_rect
			(start 0.5842 1.3335)
			(end -0.5842 -1.3335)
			(stroke
				(width 0)
				(type default)
			)
			(fill no)
			(layer "B.CrtYd")
		)
		(fp_rect
			(start 0.5842 1.3335)
			(end -0.5842 -1.3335)
			(stroke
				(width 0)
				(type default)
			)
			(fill no)
			(layer "B.Fab")
		)
		(pad "1" smd custom
			(at 0 -0.762 270)
			(size 0.2159 0.2159)
			(layers "B.Cu" "B.Mask" "B.Paste")
			(net "ADCAV33")
			(options
				(clearance outline)
				(anchor circle)
			)
			(primitives
				(gr_poly
					(pts
						(arc
							(start -0.3302 0.4318)
							(mid -0.402042 0.402042)
							(end -0.4318 0.3302)
						)
						(arc
							(start -0.4318 -0.3302)
							(mid -0.402042 -0.402042)
							(end -0.3302 -0.4318)
						)
						(arc
							(start 0.3302 -0.4318)
							(mid 0.402042 -0.402042)
							(end 0.4318 -0.3302)
						)
						(arc
							(start 0.4318 0.3302)
							(mid 0.402042 0.402042)
							(end 0.3302 0.4318)
						)
					)
					(width 0)
					(fill yes)
				)
			)
		)
		(pad "2" smd custom
			(at 0 0.762 270)
			(size 0.2159 0.2159)
			(layers "B.Cu" "B.Mask" "B.Paste")
			(net "GND")
			(options
				(clearance outline)
				(anchor circle)
			)
			(primitives
				(gr_poly
					(pts
						(arc
							(start -0.3302 0.4318)
							(mid -0.402042 0.402042)
							(end -0.4318 0.3302)
						)
						(arc
							(start -0.4318 -0.3302)
							(mid -0.402042 -0.402042)
							(end -0.3302 -0.4318)
						)
						(arc
							(start 0.3302 -0.4318)
							(mid 0.402042 -0.402042)
							(end 0.4318 -0.3302)
						)
						(arc
							(start 0.4318 0.3302)
							(mid 0.402042 0.402042)
							(end 0.3302 0.4318)
						)
					)
					(width 0)
					(fill yes)
				)
			)
		)
	)
	(footprint ""
		(layer "B.Cu")
		(at 181.3814 -60.6552)
		(property "Reference" "TP163"
			(at 0 0 0)
			(layer "B.SilkS")
			(hide yes)
			(effects
				(font
					(size 1.27 1.27)
				)
				(justify mirror)
			)
		)
		(property "Value" "TPAD28-2-GP"
			(at 0.0127 -1.6637 0)
			(unlocked yes)
			(layer "B.Fab")
			(hide yes)
			(effects
				(font
					(size 1.016 1.016)
					(thickness 0.1524)
				)
				(justify mirror)
			)
		)
		(property "Device Type" "TPAD28"
			(at 0.0127 -3.1877 0)
			(unlocked yes)
			(layer "B.Fab")
			(hide yes)
			(effects
				(font
					(size 1.016 1.016)
					(thickness 0.1524)
				)
				(justify mirror)
			)
		)
		(duplicate_pad_numbers_are_jumpers no)
		(fp_poly
			(pts
				(arc
					(start 0.3556 0)
					(mid -0.3556 0)
					(end 0.3556 0)
				)
			)
			(stroke
				(width 0)
				(type default)
			)
			(fill no)
			(layer "B.CrtYd")
		)
		(fp_poly
			(pts
				(arc
					(start 0.6096 0)
					(mid -0.6096 0)
					(end 0.6096 0)
				)
			)
			(stroke
				(width 0)
				(type default)
			)
			(fill no)
			(layer "B.Fab")
		)
		(pad "1" smd circle
			(at 0 0 180)
			(size 0.7112 0.7112)
			(layers "B.Cu" "B.Mask" "B.Paste")
			(net "XM_ADDR_24")
		)
	)
	(footprint ""
		(layer "B.Cu")
		(at 83.213448 -59.830716 180)
		(property "Reference" "C512"
			(at 0 0 0)
			(layer "B.SilkS")
			(hide yes)
			(effects
				(font
					(size 1.27 1.27)
				)
				(justify mirror)
			)
		)
		(property "Value" "SC10U16V5KX-7-GP-U"
			(at 0.0762 -6.1214 180)
			(unlocked yes)
			(layer "B.Fab")
			(hide yes)
			(effects
				(font
					(size 1.016 1.016)
					(thickness 0.1524)
				)
				(justify mirror)
			)
		)
		(property "Device Type" "C805H58"
			(at 0.0762 -8.1534 180)
			(unlocked yes)
			(layer "B.Fab")
			(hide yes)
			(effects
				(font
					(size 1.016 1.016)
					(thickness 0.1524)
				)
				(justify mirror)
			)
		)
		(duplicate_pad_numbers_are_jumpers no)
		(fp_line
			(start -0.635 0)
			(end 0.635 0)
			(stroke
				(width 0.508)
				(type default)
			)
			(layer "B.SilkS")
		)
		(fp_rect
			(start 0.9652 1.778)
			(end -0.9652 -1.778)
			(stroke
				(width 0)
				(type default)
			)
			(fill no)
			(layer "B.CrtYd")
		)
		(fp_poly
			(pts
				(xy 0.9652 -1.778) (xy -0.9652 -1.778) (xy -0.9652 1.778) (xy 0.9652 1.778)
			)
			(stroke
				(width 0)
				(type default)
			)
			(fill no)
			(layer "B.Fab")
		)
		(pad "1" smd rect
			(at 0 -0.9652)
			(size 1.397 1.143)
			(layers "B.Cu" "B.Mask" "B.Paste")
			(net "P3V3_STBY")
		)
		(pad "2" smd rect
			(at 0 0.9652)
			(size 1.397 1.143)
			(layers "B.Cu" "B.Mask" "B.Paste")
			(net "GND")
		)
	)
	(footprint ""
		(layer "B.Cu")
		(at 199.826626 -55.390796 90)
		(property "Reference" "C436"
			(at 0 0 90)
			(layer "B.SilkS")
			(hide yes)
			(effects
				(font
					(size 1.27 1.27)
				)
				(justify mirror)
			)
		)
		(property "Value" "SCD1U16V2KX-3GP"
			(at -1.1811 -2.7051 90)
			(unlocked yes)
			(layer "B.Fab")
			(hide yes)
			(effects
				(font
					(size 1.016 1.016)
					(thickness 0.1524)
				)
				(justify mirror)
			)
		)
		(property "Device Type" "C402H22"
			(at -1.1811 -4.2291 90)
			(unlocked yes)
			(layer "B.Fab")
			(hide yes)
			(effects
				(font
					(size 1.016 1.016)
					(thickness 0.1524)
				)
				(justify mirror)
			)
		)
		(duplicate_pad_numbers_are_jumpers no)
		(fp_rect
			(start 0.4318 0.9525)
			(end -0.4318 -0.9525)
			(stroke
				(width 0)
				(type default)
			)
			(fill no)
			(layer "B.CrtYd")
		)
		(fp_rect
			(start 0.4318 0.9525)
			(end -0.4318 -0.9525)
			(stroke
				(width 0)
				(type default)
			)
			(fill no)
			(layer "B.Fab")
		)
		(pad "1" smd custom
			(at 0 -0.4445 270)
			(size 0.1524 0.1524)
			(layers "B.Cu" "B.Mask" "B.Paste")
			(net "P1V8")
			(options
				(clearance outline)
				(anchor circle)
			)
			(primitives
				(gr_poly
					(pts
						(arc
							(start 0.3048 0.2032)
							(mid 0.275042 0.275042)
							(end 0.2032 0.3048)
						)
						(arc
							(start -0.2032 0.3048)
							(mid -0.275042 0.275042)
							(end -0.3048 0.2032)
						)
						(arc
							(start -0.3048 -0.2032)
							(mid -0.275042 -0.275042)
							(end -0.2032 -0.3048)
						)
						(arc
							(start 0.2032 -0.3048)
							(mid 0.275042 -0.275042)
							(end 0.3048 -0.2032)
						)
					)
					(width 0)
					(fill yes)
				)
			)
		)
		(pad "2" smd custom
			(at 0 0.4445 270)
			(size 0.1524 0.1524)
			(layers "B.Cu" "B.Mask" "B.Paste")
			(net "GND")
			(options
				(clearance outline)
				(anchor circle)
			)
			(primitives
				(gr_poly
					(pts
						(arc
							(start 0.3048 0.2032)
							(mid 0.275042 0.275042)
							(end 0.2032 0.3048)
						)
						(arc
							(start -0.2032 0.3048)
							(mid -0.275042 0.275042)
							(end -0.3048 0.2032)
						)
						(arc
							(start -0.3048 -0.2032)
							(mid -0.275042 -0.275042)
							(end -0.2032 -0.3048)
						)
						(arc
							(start 0.2032 -0.3048)
							(mid 0.275042 -0.275042)
							(end 0.3048 -0.2032)
						)
					)
					(width 0)
					(fill yes)
				)
			)
		)
	)
	(footprint ""
		(layer "B.Cu")
		(at 10.211562 -139.575032 90)
		(property "Reference" "R233"
			(at 0 0 90)
			(layer "B.SilkS")
			(hide yes)
			(effects
				(font
					(size 1.27 1.27)
				)
				(justify mirror)
			)
		)
		(property "Value" "120R2F-GP"
			(at -0.064008 -3.993896 90)
			(unlocked yes)
			(layer "B.Fab")
			(hide yes)
			(effects
				(font
					(size 1.016 1.016)
					(thickness 0.1524)
				)
				(justify mirror)
			)
		)
		(property "Device Type" "R402H16"
			(at -0.064008 -5.517896 90)
			(unlocked yes)
			(layer "B.Fab")
			(hide yes)
			(effects
				(font
					(size 1.016 1.016)
					(thickness 0.1524)
				)
				(justify mirror)
			)
		)
		(duplicate_pad_numbers_are_jumpers no)
		(fp_line
			(start 0.508 -0.9398)
			(end 0.508 0.9398)
			(stroke
				(width 0.1524)
				(type default)
			)
			(layer "B.SilkS")
		)
		(fp_line
			(start -0.508 -0.9398)
			(end 0.508 -0.9398)
			(stroke
				(width 0.1524)
				(type default)
			)
			(layer "B.SilkS")
		)
		(fp_rect
			(start 0.508 0.9398)
			(end -0.508 -0.9398)
			(stroke
				(width 0)
				(type default)
			)
			(fill no)
			(layer "B.CrtYd")
		)
		(fp_rect
			(start 0.508 0.9398)
			(end -0.508 -0.9398)
			(stroke
				(width 0)
				(type default)
			)
			(fill no)
			(layer "B.Fab")
		)
		(pad "1" smd custom
			(at 0 -0.4445 270)
			(size 0.1397 0.1397)
			(layers "B.Cu" "B.Mask" "B.Paste")
			(net "GND")
			(options
				(clearance outline)
				(anchor circle)
			)
			(primitives
				(gr_poly
					(pts
						(arc
							(start -0.1778 0.2794)
							(mid -0.249642 0.249642)
							(end -0.2794 0.1778)
						)
						(arc
							(start -0.2794 -0.1778)
							(mid -0.249642 -0.249642)
							(end -0.1778 -0.2794)
						)
						(arc
							(start 0.1778 -0.2794)
							(mid 0.249642 -0.249642)
							(end 0.2794 -0.1778)
						)
						(arc
							(start 0.2794 0.1778)
							(mid 0.249642 0.249642)
							(end 0.1778 0.2794)
						)
					)
					(width 0)
					(fill yes)
				)
			)
		)
		(pad "2" smd custom
			(at 0 0.4445 270)
			(size 0.1397 0.1397)
			(layers "B.Cu" "B.Mask" "B.Paste")
			(net "MEMA_0")
			(options
				(clearance outline)
				(anchor circle)
			)
			(primitives
				(gr_poly
					(pts
						(arc
							(start -0.1778 0.2794)
							(mid -0.249642 0.249642)
							(end -0.2794 0.1778)
						)
						(arc
							(start -0.2794 -0.1778)
							(mid -0.249642 -0.249642)
							(end -0.1778 -0.2794)
						)
						(arc
							(start 0.1778 -0.2794)
							(mid 0.249642 -0.249642)
							(end 0.2794 -0.1778)
						)
						(arc
							(start 0.2794 0.1778)
							(mid 0.249642 0.249642)
							(end 0.1778 0.2794)
						)
					)
					(width 0)
					(fill yes)
				)
			)
		)
	)
	(footprint ""
		(layer "B.Cu")
		(at 197.819518 -81.153 180)
		(property "Reference" "C295"
			(at 0 0 0)
			(layer "B.SilkS")
			(hide yes)
			(effects
				(font
					(size 1.27 1.27)
				)
				(justify mirror)
			)
		)
		(property "Value" "SCD22U10V1KX-GP"
			(at 2.8321 -1.7399 180)
			(unlocked yes)
			(layer "B.Fab")
			(hide yes)
			(effects
				(font
					(size 1.016 1.016)
					(thickness 0.1524)
				)
				(justify mirror)
			)
		)
		(property "Device Type" "C0201H13"
			(at 2.8321 -3.2639 180)
			(unlocked yes)
			(layer "B.Fab")
			(hide yes)
			(effects
				(font
					(size 1.016 1.016)
					(thickness 0.1524)
				)
				(justify mirror)
			)
		)
		(duplicate_pad_numbers_are_jumpers no)
		(fp_rect
			(start 0.2794 0.6477)
			(end -0.2794 -0.6477)
			(stroke
				(width 0)
				(type default)
			)
			(fill no)
			(layer "B.CrtYd")
		)
		(fp_rect
			(start 0.2794 0.6477)
			(end -0.2794 -0.6477)
			(stroke
				(width 0)
				(type default)
			)
			(fill no)
			(layer "B.Fab")
		)
		(pad "1" smd custom
			(at 0 -0.2794)
			(size 0.0762 0.0762)
			(layers "B.Cu" "B.Mask" "B.Paste")
			(net "PCIE_IOM_TO_COMP_11_DP_C")
			(options
				(clearance outline)
				(anchor circle)
			)
			(primitives
				(gr_poly
					(pts
						(arc
							(start 0.1524 0.127)
							(mid 0.137521 0.162921)
							(end 0.1016 0.1778)
						)
						(arc
							(start -0.1016 0.1778)
							(mid -0.137521 0.162921)
							(end -0.1524 0.127)
						)
						(arc
							(start -0.1524 -0.127)
							(mid -0.137521 -0.162921)
							(end -0.1016 -0.1778)
						)
						(arc
							(start 0.1016 -0.1778)
							(mid 0.137521 -0.162921)
							(end 0.1524 -0.127)
						)
					)
					(width 0)
					(fill yes)
				)
			)
		)
		(pad "2" smd custom
			(at 0 0.2794)
			(size 0.0762 0.0762)
			(layers "B.Cu" "B.Mask" "B.Paste")
			(net "PCIE_IOM_TO_COMP_11_DP")
			(options
				(clearance outline)
				(anchor circle)
			)
			(primitives
				(gr_poly
					(pts
						(arc
							(start 0.1524 0.127)
							(mid 0.137521 0.162921)
							(end 0.1016 0.1778)
						)
						(arc
							(start -0.1016 0.1778)
							(mid -0.137521 0.162921)
							(end -0.1524 0.127)
						)
						(arc
							(start -0.1524 -0.127)
							(mid -0.137521 -0.162921)
							(end -0.1016 -0.1778)
						)
						(arc
							(start 0.1016 -0.1778)
							(mid 0.137521 -0.162921)
							(end 0.1524 -0.127)
						)
					)
					(width 0)
					(fill yes)
				)
			)
		)
	)
)
